(kicad_pcb
	(version 20260206)
	(generator "pcbnew")
	(generator_version "10.0")
	(general
		(thickness 1.6)
		(legacy_teardrops no)
	)
	(paper "A4")
	(title_block
		(title "12092022_DA0F0TMDCD0_F0T_Management_Board_D_brd_V3_OCP.brd")
		(comment 1 "Grand Teton / footprints 461-466 of 1440")
	)
	(layers
		(0 "F.Cu" signal "TOP")
		(4 "In1.Cu" signal "GND")
		(6 "In2.Cu" signal "IN1")
		(8 "In3.Cu" signal "GND1")
		(10 "In4.Cu" signal "IN2")
		(12 "In5.Cu" signal "VCC")
		(14 "In6.Cu" signal "VCC1")
		(16 "In7.Cu" signal "IN3")
		(18 "In8.Cu" signal "GND2")
		(20 "In9.Cu" signal "IN4")
		(22 "In10.Cu" signal "GND3")
		(2 "B.Cu" signal "BOTTOM")
		(9 "F.Adhes" user "F.Adhesive")
		(11 "B.Adhes" user "B.Adhesive")
		(13 "F.Paste" user "Package Geometry/Pastemask Top")
		(15 "B.Paste" user "Package Geometry/Pastemask Bottom")
		(5 "F.SilkS" user "Ref Des/Silkscreen Top")
		(7 "B.SilkS" user "Ref Des/Silkscreen Bottom")
		(1 "F.Mask" user "Board Geometry/Soldermask Top")
		(3 "B.Mask" user "Board Geometry/Soldermask Bottom")
		(17 "Dwgs.User" user "User.Drawings")
		(19 "Cmts.User" user "User.Comments")
		(21 "Eco1.User" user "User.Eco1")
		(23 "Eco2.User" user "User.Eco2")
		(25 "Edge.Cuts" user "Board Geometry/Outline")
		(27 "Margin" user)
		(31 "F.CrtYd" user "Package Geometry/Place Bound Top")
		(29 "B.CrtYd" user "Package Geometry/Place Bound Bottom")
		(35 "F.Fab" user "Ref Des/Assembly Top")
		(33 "B.Fab" user "Ref Des/Assembly Bottom")
	)
	(footprint ""
		(layer "F.Cu")
		(at 13.262864 -8.857742)
		(property "Reference" "R734"
			(at 0 0 0)
			(layer "F.SilkS")
			(hide yes)
			(effects
				(font
					(size 1.27 1.27)
				)
			)
		)
		(property "Value" ""
			(at 0 0 0)
			(layer "F.Fab")
			(effects
				(font
					(size 1.27 1.27)
				)
			)
		)
		(duplicate_pad_numbers_are_jumpers no)
		(fp_line
			(start -0.7874 -0.4064)
			(end 0.7874 -0.4064)
			(stroke
				(width 0.1524)
				(type default)
			)
			(layer "F.SilkS")
		)
		(fp_line
			(start -0.7874 0.4064)
			(end -0.7874 -0.4064)
			(stroke
				(width 0.1524)
				(type default)
			)
			(layer "F.SilkS")
		)
		(fp_line
			(start 0.7874 -0.4064)
			(end 0.7874 0.4064)
			(stroke
				(width 0.1524)
				(type default)
			)
			(layer "F.SilkS")
		)
		(fp_line
			(start 0.7874 0.4064)
			(end -0.7874 0.4064)
			(stroke
				(width 0.1524)
				(type default)
			)
			(layer "F.SilkS")
		)
		(fp_line
			(start -0.67945 -0.305054)
			(end -0.12065 -0.305054)
			(stroke
				(width 0.1)
				(type default)
			)
			(layer "F.Fab")
		)
		(fp_line
			(start -0.67945 0.3048)
			(end -0.67945 -0.305054)
			(stroke
				(width 0.1)
				(type default)
			)
			(layer "F.Fab")
		)
		(fp_line
			(start -0.12065 -0.305054)
			(end -0.12065 -0.2794)
			(stroke
				(width 0.1)
				(type default)
			)
			(layer "F.Fab")
		)
		(fp_line
			(start -0.12065 -0.2794)
			(end 0.12065 -0.2794)
			(stroke
				(width 0.1)
				(type default)
			)
			(layer "F.Fab")
		)
		(fp_line
			(start -0.12065 0.2794)
			(end -0.12065 0.3048)
			(stroke
				(width 0.1)
				(type default)
			)
			(layer "F.Fab")
		)
		(fp_line
			(start -0.12065 0.3048)
			(end -0.67945 0.3048)
			(stroke
				(width 0.1)
				(type default)
			)
			(layer "F.Fab")
		)
		(fp_line
			(start 0.120396 0.2794)
			(end -0.12065 0.2794)
			(stroke
				(width 0.1)
				(type default)
			)
			(layer "F.Fab")
		)
		(fp_line
			(start 0.120396 0.3048)
			(end 0.120396 0.2794)
			(stroke
				(width 0.1)
				(type default)
			)
			(layer "F.Fab")
		)
		(fp_line
			(start 0.12065 -0.3048)
			(end 0.67945 -0.3048)
			(stroke
				(width 0.1)
				(type default)
			)
			(layer "F.Fab")
		)
		(fp_line
			(start 0.12065 -0.2794)
			(end 0.12065 -0.3048)
			(stroke
				(width 0.1)
				(type default)
			)
			(layer "F.Fab")
		)
		(fp_line
			(start 0.67945 -0.3048)
			(end 0.67945 0.3048)
			(stroke
				(width 0.1)
				(type default)
			)
			(layer "F.Fab")
		)
		(fp_line
			(start 0.67945 0.3048)
			(end 0.120396 0.3048)
			(stroke
				(width 0.1)
				(type default)
			)
			(layer "F.Fab")
		)
		(pad "1" smd circle
			(at -0.40005 0)
			(size 0 0)
			(layers "F.Cu" "F.Mask" "F.Paste")
			(net "REAR_PWR_BTN_N")
		)
		(pad "2" smd circle
			(at 0.40005 0)
			(size 0 0)
			(layers "F.Cu" "F.Mask" "F.Paste")
			(net "FM_DEBUG_PWR_BTN_N")
		)
	)
	(footprint ""
		(layer "F.Cu")
		(at 22.225 -68.834 -90)
		(property "Reference" "R562"
			(at 0 0 270)
			(layer "F.SilkS")
			(hide yes)
			(effects
				(font
					(size 1.27 1.27)
				)
			)
		)
		(property "Value" ""
			(at 0 0 270)
			(layer "F.Fab")
			(effects
				(font
					(size 1.27 1.27)
				)
			)
		)
		(duplicate_pad_numbers_are_jumpers no)
		(fp_line
			(start -0.7874 0.4064)
			(end -0.7874 -0.4064)
			(stroke
				(width 0.1524)
				(type default)
			)
			(layer "F.SilkS")
		)
		(fp_line
			(start 0.7874 0.4064)
			(end -0.7874 0.4064)
			(stroke
				(width 0.1524)
				(type default)
			)
			(layer "F.SilkS")
		)
		(fp_line
			(start -0.7874 -0.4064)
			(end 0.7874 -0.4064)
			(stroke
				(width 0.1524)
				(type default)
			)
			(layer "F.SilkS")
		)
		(fp_line
			(start 0.7874 -0.4064)
			(end 0.7874 0.4064)
			(stroke
				(width 0.1524)
				(type default)
			)
			(layer "F.SilkS")
		)
		(fp_line
			(start -0.67945 0.3048)
			(end -0.67945 -0.305054)
			(stroke
				(width 0.1)
				(type default)
			)
			(layer "F.Fab")
		)
		(fp_line
			(start -0.12065 0.3048)
			(end -0.67945 0.3048)
			(stroke
				(width 0.1)
				(type default)
			)
			(layer "F.Fab")
		)
		(fp_line
			(start 0.120396 0.3048)
			(end 0.120396 0.2794)
			(stroke
				(width 0.1)
				(type default)
			)
			(layer "F.Fab")
		)
		(fp_line
			(start 0.67945 0.3048)
			(end 0.120396 0.3048)
			(stroke
				(width 0.1)
				(type default)
			)
			(layer "F.Fab")
		)
		(fp_line
			(start -0.12065 0.2794)
			(end -0.12065 0.3048)
			(stroke
				(width 0.1)
				(type default)
			)
			(layer "F.Fab")
		)
		(fp_line
			(start 0.120396 0.2794)
			(end -0.12065 0.2794)
			(stroke
				(width 0.1)
				(type default)
			)
			(layer "F.Fab")
		)
		(fp_line
			(start -0.12065 -0.2794)
			(end 0.12065 -0.2794)
			(stroke
				(width 0.1)
				(type default)
			)
			(layer "F.Fab")
		)
		(fp_line
			(start 0.12065 -0.2794)
			(end 0.12065 -0.3048)
			(stroke
				(width 0.1)
				(type default)
			)
			(layer "F.Fab")
		)
		(fp_line
			(start 0.12065 -0.3048)
			(end 0.67945 -0.3048)
			(stroke
				(width 0.1)
				(type default)
			)
			(layer "F.Fab")
		)
		(fp_line
			(start 0.67945 -0.3048)
			(end 0.67945 0.3048)
			(stroke
				(width 0.1)
				(type default)
			)
			(layer "F.Fab")
		)
		(fp_line
			(start -0.67945 -0.305054)
			(end -0.12065 -0.305054)
			(stroke
				(width 0.1)
				(type default)
			)
			(layer "F.Fab")
		)
		(fp_line
			(start -0.12065 -0.305054)
			(end -0.12065 -0.2794)
			(stroke
				(width 0.1)
				(type default)
			)
			(layer "F.Fab")
		)
		(pad "1" smd circle
			(at -0.40005 0 270)
			(size 0 0)
			(layers "F.Cu" "F.Mask" "F.Paste")
			(net "RST_SPI_BMC_FLASH_R1_N")
		)
		(pad "2" smd circle
			(at 0.40005 0 270)
			(size 0 0)
			(layers "F.Cu" "F.Mask" "F.Paste")
			(net "RST_SPI_FLASH_BUF_N")
		)
	)
	(footprint ""
		(layer "F.Cu")
		(at 114.554 82.1436 -90)
		(property "Reference" "X23"
			(at -1.96723 3.1115 0)
			(unlocked yes)
			(layer "F.SilkS")
			(effects
				(font
					(size 0.7874 0.5842)
					(thickness 0.1524)
				)
				(justify left)
			)
		)
		(property "Value" ""
			(at 0 0 270)
			(layer "F.Fab")
			(effects
				(font
					(size 1.27 1.27)
				)
			)
		)
		(property "Device Type" "TP_TDR_4P_FTS_TH-TP_TDR_4P_DIPA"
			(at 1.30175 1.27 0)
			(unlocked yes)
			(layer "F.Fab")
			(hide yes)
			(effects
				(font
					(size 0.635 0.4064)
					(thickness 0.1524)
				)
			)
		)
		(property "User Part Number" "N_A"
			(at 1.30175 1.27 0)
			(unlocked yes)
			(layer "Cmts.User")
			(hide yes)
			(effects
				(font
					(size 0.635 0.4064)
					(thickness 0.1524)
				)
			)
		)
		(duplicate_pad_numbers_are_jumpers no)
		(fp_line
			(start 0 3.81)
			(end 2.54 3.81)
			(stroke
				(width 0.1524)
				(type default)
			)
			(layer "F.SilkS")
		)
		(fp_line
			(start 2.54 3.81)
			(end 2.54 3.6703)
			(stroke
				(width 0.1524)
				(type default)
			)
			(layer "F.SilkS")
		)
		(fp_line
			(start 0 3.175)
			(end 0 3.81)
			(stroke
				(width 0.1524)
				(type default)
			)
			(layer "F.SilkS")
		)
		(fp_line
			(start 2.54 1.4097)
			(end 2.54 1.1303)
			(stroke
				(width 0.1524)
				(type default)
			)
			(layer "F.SilkS")
		)
		(fp_line
			(start 0 0.635)
			(end 0 1.905)
			(stroke
				(width 0.1524)
				(type default)
			)
			(layer "F.SilkS")
		)
		(fp_line
			(start 2.54 -1.1303)
			(end 2.54 -1.27)
			(stroke
				(width 0.1524)
				(type default)
			)
			(layer "F.SilkS")
		)
		(fp_line
			(start 0 -1.27)
			(end 0 -0.635)
			(stroke
				(width 0.1524)
				(type default)
			)
			(layer "F.SilkS")
		)
		(fp_line
			(start 2.54 -1.27)
			(end 0 -1.27)
			(stroke
				(width 0.1524)
				(type default)
			)
			(layer "F.SilkS")
		)
		(fp_poly
			(pts
				(xy -0.761746 0) (xy -2.285746 -0.762) (xy -2.285746 0.762)
			)
			(stroke
				(width 0)
				(type default)
			)
			(fill yes)
			(layer "F.SilkS")
		)
		(fp_line
			(start 0 3.81)
			(end 2.54 3.81)
			(stroke
				(width 0.1)
				(type default)
			)
			(layer "F.Fab")
		)
		(fp_line
			(start 2.54 3.81)
			(end 2.54 -1.27)
			(stroke
				(width 0.1)
				(type default)
			)
			(layer "F.Fab")
		)
		(fp_line
			(start 0 -1.27)
			(end 0 3.81)
			(stroke
				(width 0.1)
				(type default)
			)
			(layer "F.Fab")
		)
		(fp_line
			(start 2.54 -1.27)
			(end 0 -1.27)
			(stroke
				(width 0.1)
				(type default)
			)
			(layer "F.Fab")
		)
		(fp_poly
			(pts
				(xy -0.761746 0) (xy -2.285746 -0.762) (xy -2.285746 0.762)
			)
			(stroke
				(width 0)
				(type default)
			)
			(fill yes)
			(layer "F.Fab")
		)
		(pad "1" thru_hole circle
			(at 0 0 270)
			(size 1.0033 1.0033)
			(drill 0.249936)
			(layers "*.Cu" "*.Mask")
			(remove_unused_layers no)
			(net "TDR_DIFF_100_IN4_DN")
			(clearance 0.10795)
			(thermal_gap 0.10795)
			(padstack
				(mode front_inner_back)
				(layer "Inner"
					(shape circle)
					(size 0.8001 0.8001)
					(clearance 0.1524)
				)
				(layer "B.Cu"
					(shape circle)
					(size 1.0033 1.0033)
					(clearance 0.10795)
				)
			)
		)
		(pad "2" thru_hole circle
			(at 2.54 0 270)
			(size 1.9939 1.9939)
			(drill 0.249936)
			(layers "*.Cu" "*.Mask")
			(remove_unused_layers no)
			(net "GND_P1")
			(clearance 0.10795)
			(thermal_gap 0.10795)
			(padstack
				(mode front_inner_back)
				(layer "Inner"
					(shape circle)
					(size 0.8001 0.8001)
					(clearance 0.1524)
				)
				(layer "B.Cu"
					(shape circle)
					(size 1.9939 1.9939)
					(clearance 0.10795)
				)
			)
		)
		(pad "3" thru_hole circle
			(at 2.54 2.54 270)
			(size 1.9939 1.9939)
			(drill 0.249936)
			(layers "*.Cu" "*.Mask")
			(remove_unused_layers no)
			(net "GND_P1")
			(clearance 0.10795)
			(thermal_gap 0.10795)
			(padstack
				(mode front_inner_back)
				(layer "Inner"
					(shape circle)
					(size 0.8001 0.8001)
					(clearance 0.1524)
				)
				(layer "B.Cu"
					(shape circle)
					(size 1.9939 1.9939)
					(clearance 0.10795)
				)
			)
		)
		(pad "4" thru_hole circle
			(at 0 2.54 270)
			(size 1.0033 1.0033)
			(drill 0.249936)
			(layers "*.Cu" "*.Mask")
			(remove_unused_layers no)
			(net "TDR_DIFF_100_IN4_DP")
			(clearance 0.10795)
			(thermal_gap 0.10795)
			(padstack
				(mode front_inner_back)
				(layer "Inner"
					(shape circle)
					(size 0.8001 0.8001)
					(clearance 0.1524)
				)
				(layer "B.Cu"
					(shape circle)
					(size 1.0033 1.0033)
					(clearance 0.10795)
				)
			)
		)
	)
	(footprint ""
		(layer "F.Cu")
		(at 12.319 -82.296 180)
		(property "Reference" "R437"
			(at 0 0 180)
			(layer "F.SilkS")
			(hide yes)
			(effects
				(font
					(size 1.27 1.27)
				)
			)
		)
		(property "Value" ""
			(at 0 0 180)
			(layer "F.Fab")
			(effects
				(font
					(size 1.27 1.27)
				)
			)
		)
		(duplicate_pad_numbers_are_jumpers no)
		(fp_line
			(start 0.7874 0.4064)
			(end -0.7874 0.4064)
			(stroke
				(width 0.1524)
				(type default)
			)
			(layer "F.SilkS")
		)
		(fp_line
			(start 0.7874 -0.4064)
			(end 0.7874 0.4064)
			(stroke
				(width 0.1524)
				(type default)
			)
			(layer "F.SilkS")
		)
		(fp_line
			(start -0.7874 0.4064)
			(end -0.7874 -0.4064)
			(stroke
				(width 0.1524)
				(type default)
			)
			(layer "F.SilkS")
		)
		(fp_line
			(start -0.7874 -0.4064)
			(end 0.7874 -0.4064)
			(stroke
				(width 0.1524)
				(type default)
			)
			(layer "F.SilkS")
		)
		(fp_line
			(start 0.67945 0.3048)
			(end 0.120396 0.3048)
			(stroke
				(width 0.1)
				(type default)
			)
			(layer "F.Fab")
		)
		(fp_line
			(start 0.67945 -0.3048)
			(end 0.67945 0.3048)
			(stroke
				(width 0.1)
				(type default)
			)
			(layer "F.Fab")
		)
		(fp_line
			(start 0.12065 -0.2794)
			(end 0.12065 -0.3048)
			(stroke
				(width 0.1)
				(type default)
			)
			(layer "F.Fab")
		)
		(fp_line
			(start 0.12065 -0.3048)
			(end 0.67945 -0.3048)
			(stroke
				(width 0.1)
				(type default)
			)
			(layer "F.Fab")
		)
		(fp_line
			(start 0.120396 0.3048)
			(end 0.120396 0.2794)
			(stroke
				(width 0.1)
				(type default)
			)
			(layer "F.Fab")
		)
		(fp_line
			(start 0.120396 0.2794)
			(end -0.12065 0.2794)
			(stroke
				(width 0.1)
				(type default)
			)
			(layer "F.Fab")
		)
		(fp_line
			(start -0.12065 0.3048)
			(end -0.67945 0.3048)
			(stroke
				(width 0.1)
				(type default)
			)
			(layer "F.Fab")
		)
		(fp_line
			(start -0.12065 0.2794)
			(end -0.12065 0.3048)
			(stroke
				(width 0.1)
				(type default)
			)
			(layer "F.Fab")
		)
		(fp_line
			(start -0.12065 -0.2794)
			(end 0.12065 -0.2794)
			(stroke
				(width 0.1)
				(type default)
			)
			(layer "F.Fab")
		)
		(fp_line
			(start -0.12065 -0.305054)
			(end -0.12065 -0.2794)
			(stroke
				(width 0.1)
				(type default)
			)
			(layer "F.Fab")
		)
		(fp_line
			(start -0.67945 0.3048)
			(end -0.67945 -0.305054)
			(stroke
				(width 0.1)
				(type default)
			)
			(layer "F.Fab")
		)
		(fp_line
			(start -0.67945 -0.305054)
			(end -0.12065 -0.305054)
			(stroke
				(width 0.1)
				(type default)
			)
			(layer "F.Fab")
		)
		(pad "1" smd circle
			(at -0.40005 0 180)
			(size 0 0)
			(layers "F.Cu" "F.Mask" "F.Paste")
			(net "SGPIO_PLD_DI_0")
		)
		(pad "2" smd circle
			(at 0.40005 0 180)
			(size 0 0)
			(layers "F.Cu" "F.Mask" "F.Paste")
			(net "SGPIO_DI_0")
		)
	)
	(footprint ""
		(layer "F.Cu")
		(at 13.5636 -56.0324)
		(property "Reference" "R529"
			(at 0 0 0)
			(layer "F.SilkS")
			(hide yes)
			(effects
				(font
					(size 1.27 1.27)
				)
			)
		)
		(property "Value" ""
			(at 0 0 0)
			(layer "F.Fab")
			(effects
				(font
					(size 1.27 1.27)
				)
			)
		)
		(duplicate_pad_numbers_are_jumpers no)
		(fp_line
			(start -0.7874 -0.4064)
			(end 0.7874 -0.4064)
			(stroke
				(width 0.1524)
				(type default)
			)
			(layer "F.SilkS")
		)
		(fp_line
			(start -0.7874 0.4064)
			(end -0.7874 -0.4064)
			(stroke
				(width 0.1524)
				(type default)
			)
			(layer "F.SilkS")
		)
		(fp_line
			(start 0.7874 -0.4064)
			(end 0.7874 0.4064)
			(stroke
				(width 0.1524)
				(type default)
			)
			(layer "F.SilkS")
		)
		(fp_line
			(start 0.7874 0.4064)
			(end -0.7874 0.4064)
			(stroke
				(width 0.1524)
				(type default)
			)
			(layer "F.SilkS")
		)
		(fp_line
			(start -0.67945 -0.305054)
			(end -0.12065 -0.305054)
			(stroke
				(width 0.1)
				(type default)
			)
			(layer "F.Fab")
		)
		(fp_line
			(start -0.67945 0.3048)
			(end -0.67945 -0.305054)
			(stroke
				(width 0.1)
				(type default)
			)
			(layer "F.Fab")
		)
		(fp_line
			(start -0.12065 -0.305054)
			(end -0.12065 -0.2794)
			(stroke
				(width 0.1)
				(type default)
			)
			(layer "F.Fab")
		)
		(fp_line
			(start -0.12065 -0.2794)
			(end 0.12065 -0.2794)
			(stroke
				(width 0.1)
				(type default)
			)
			(layer "F.Fab")
		)
		(fp_line
			(start -0.12065 0.2794)
			(end -0.12065 0.3048)
			(stroke
				(width 0.1)
				(type default)
			)
			(layer "F.Fab")
		)
		(fp_line
			(start -0.12065 0.3048)
			(end -0.67945 0.3048)
			(stroke
				(width 0.1)
				(type default)
			)
			(layer "F.Fab")
		)
		(fp_line
			(start 0.120396 0.2794)
			(end -0.12065 0.2794)
			(stroke
				(width 0.1)
				(type default)
			)
			(layer "F.Fab")
		)
		(fp_line
			(start 0.120396 0.3048)
			(end 0.120396 0.2794)
			(stroke
				(width 0.1)
				(type default)
			)
			(layer "F.Fab")
		)
		(fp_line
			(start 0.12065 -0.3048)
			(end 0.67945 -0.3048)
			(stroke
				(width 0.1)
				(type default)
			)
			(layer "F.Fab")
		)
		(fp_line
			(start 0.12065 -0.2794)
			(end 0.12065 -0.3048)
			(stroke
				(width 0.1)
				(type default)
			)
			(layer "F.Fab")
		)
		(fp_line
			(start 0.67945 -0.3048)
			(end 0.67945 0.3048)
			(stroke
				(width 0.1)
				(type default)
			)
			(layer "F.Fab")
		)
		(fp_line
			(start 0.67945 0.3048)
			(end 0.120396 0.3048)
			(stroke
				(width 0.1)
				(type default)
			)
			(layer "F.Fab")
		)
		(pad "1" smd circle
			(at -0.40005 0)
			(size 0 0)
			(layers "F.Cu" "F.Mask" "F.Paste")
			(net "PWRGD_P1V8_AUX")
		)
		(pad "2" smd circle
			(at 0.40005 0)
			(size 0 0)
			(layers "F.Cu" "F.Mask" "F.Paste")
			(net "PWRGD_P1V8_AUX_R2")
		)
	)
	(footprint ""
		(layer "F.Cu")
		(at 85.654642 -58.942478 -90)
		(property "Reference" "PC255"
			(at 0 0 270)
			(layer "F.SilkS")
			(hide yes)
			(effects
				(font
					(size 1.27 1.27)
				)
			)
		)
		(property "Value" ""
			(at 0 0 270)
			(layer "F.Fab")
			(effects
				(font
					(size 1.27 1.27)
				)
			)
		)
		(duplicate_pad_numbers_are_jumpers no)
		(fp_line
			(start -0.7874 0.4064)
			(end -0.7874 -0.4064)
			(stroke
				(width 0.1524)
				(type default)
			)
			(layer "F.SilkS")
		)
		(fp_line
			(start 0.7874 0.4064)
			(end -0.7874 0.4064)
			(stroke
				(width 0.1524)
				(type default)
			)
			(layer "F.SilkS")
		)
		(fp_line
			(start -0.7874 -0.4064)
			(end 0.7874 -0.4064)
			(stroke
				(width 0.1524)
				(type default)
			)
			(layer "F.SilkS")
		)
		(fp_line
			(start 0.7874 -0.4064)
			(end 0.7874 0.4064)
			(stroke
				(width 0.1524)
				(type default)
			)
			(layer "F.SilkS")
		)
		(fp_line
			(start -0.67945 0.3048)
			(end -0.67945 -0.305054)
			(stroke
				(width 0.1)
				(type default)
			)
			(layer "F.Fab")
		)
		(fp_line
			(start -0.12065 0.3048)
			(end -0.67945 0.3048)
			(stroke
				(width 0.1)
				(type default)
			)
			(layer "F.Fab")
		)
		(fp_line
			(start 0.120396 0.3048)
			(end 0.120396 0.2794)
			(stroke
				(width 0.1)
				(type default)
			)
			(layer "F.Fab")
		)
		(fp_line
			(start 0.67945 0.3048)
			(end 0.120396 0.3048)
			(stroke
				(width 0.1)
				(type default)
			)
			(layer "F.Fab")
		)
		(fp_line
			(start -0.12065 0.2794)
			(end -0.12065 0.3048)
			(stroke
				(width 0.1)
				(type default)
			)
			(layer "F.Fab")
		)
		(fp_line
			(start 0.120396 0.2794)
			(end -0.12065 0.2794)
			(stroke
				(width 0.1)
				(type default)
			)
			(layer "F.Fab")
		)
		(fp_line
			(start -0.12065 -0.2794)
			(end 0.12065 -0.2794)
			(stroke
				(width 0.1)
				(type default)
			)
			(layer "F.Fab")
		)
		(fp_line
			(start 0.12065 -0.2794)
			(end 0.12065 -0.3048)
			(stroke
				(width 0.1)
				(type default)
			)
			(layer "F.Fab")
		)
		(fp_line
			(start 0.12065 -0.3048)
			(end 0.67945 -0.3048)
			(stroke
				(width 0.1)
				(type default)
			)
			(layer "F.Fab")
		)
		(fp_line
			(start 0.67945 -0.3048)
			(end 0.67945 0.3048)
			(stroke
				(width 0.1)
				(type default)
			)
			(layer "F.Fab")
		)
		(fp_line
			(start -0.67945 -0.305054)
			(end -0.12065 -0.305054)
			(stroke
				(width 0.1)
				(type default)
			)
			(layer "F.Fab")
		)
		(fp_line
			(start -0.12065 -0.305054)
			(end -0.12065 -0.2794)
			(stroke
				(width 0.1)
				(type default)
			)
			(layer "F.Fab")
		)
		(pad "1" smd circle
			(at -0.40005 0 270)
			(size 0 0)
			(layers "F.Cu" "F.Mask" "F.Paste")
			(net "P1V2_AUX")
		)
		(pad "2" smd circle
			(at 0.40005 0 270)
			(size 0 0)
			(layers "F.Cu" "F.Mask" "F.Paste")
			(net "GND")
		)
	)
)
